(kicad_pcb
	(version 20260206)
	(generator "pcbnew")
	(generator_version "10.0")
	(general
		(thickness 1.6)
		(legacy_teardrops no)
	)
	(paper "A4")
	(title_block
		(title "9054_F0T_PDB_BD_GPU_F_V04_1213_1550_OCP.brd")
		(comment 1 "Grand Teton / footprints 174-178 of 608")
	)
	(layers
		(0 "F.Cu" signal "TOP")
		(4 "In1.Cu" signal "GND")
		(6 "In2.Cu" signal "IN1")
		(8 "In3.Cu" signal "GND1")
		(10 "In4.Cu" signal "VCC")
		(12 "In5.Cu" signal "VCC1")
		(14 "In6.Cu" signal "GND2")
		(16 "In7.Cu" signal "IN2")
		(18 "In8.Cu" signal "GND3")
		(2 "B.Cu" signal "BOTTOM")
		(9 "F.Adhes" user "F.Adhesive")
		(11 "B.Adhes" user "B.Adhesive")
		(13 "F.Paste" user "Package Geometry/Pastemask Top")
		(15 "B.Paste" user "Package Geometry/Pastemask Bottom")
		(5 "F.SilkS" user "Ref Des/Silkscreen Top")
		(7 "B.SilkS" user "Ref Des/Silkscreen Bottom")
		(1 "F.Mask" user "Board Geometry/Soldermask Top")
		(3 "B.Mask" user "Board Geometry/Soldermask Bottom")
		(17 "Dwgs.User" user "User.Drawings")
		(19 "Cmts.User" user "User.Comments")
		(21 "Eco1.User" user "User.Eco1")
		(23 "Eco2.User" user "User.Eco2")
		(25 "Edge.Cuts" user "Board Geometry/Outline")
		(27 "Margin" user)
		(31 "F.CrtYd" user "Package Geometry/Place Bound Top")
		(29 "B.CrtYd" user "Package Geometry/Place Bound Bottom")
		(35 "F.Fab" user "Ref Des/Assembly Top")
		(33 "B.Fab" user "Ref Des/Assembly Bottom")
	)
	(footprint ""
		(layer "F.Cu")
		(at 176.1744 -63.881)
		(property "Reference" "PC578"
			(at 0 0 0)
			(layer "F.SilkS")
			(hide yes)
			(effects
				(font
					(size 1.27 1.27)
				)
			)
		)
		(property "Value" ""
			(at 0 0 0)
			(layer "F.Fab")
			(effects
				(font
					(size 1.27 1.27)
				)
			)
		)
		(duplicate_pad_numbers_are_jumpers no)
		(fp_line
			(start -0.7874 -0.4064)
			(end 0.7874 -0.4064)
			(stroke
				(width 0.1524)
				(type default)
			)
			(layer "F.SilkS")
		)
		(fp_line
			(start -0.7874 0.4064)
			(end -0.7874 -0.4064)
			(stroke
				(width 0.1524)
				(type default)
			)
			(layer "F.SilkS")
		)
		(fp_line
			(start 0.7874 -0.4064)
			(end 0.7874 0.4064)
			(stroke
				(width 0.1524)
				(type default)
			)
			(layer "F.SilkS")
		)
		(fp_line
			(start 0.7874 0.4064)
			(end -0.7874 0.4064)
			(stroke
				(width 0.1524)
				(type default)
			)
			(layer "F.SilkS")
		)
		(fp_line
			(start -0.67945 -0.305054)
			(end -0.12065 -0.305054)
			(stroke
				(width 0.1)
				(type default)
			)
			(layer "F.Fab")
		)
		(fp_line
			(start -0.67945 0.3048)
			(end -0.67945 -0.305054)
			(stroke
				(width 0.1)
				(type default)
			)
			(layer "F.Fab")
		)
		(fp_line
			(start -0.12065 -0.305054)
			(end -0.12065 -0.2794)
			(stroke
				(width 0.1)
				(type default)
			)
			(layer "F.Fab")
		)
		(fp_line
			(start -0.12065 -0.2794)
			(end 0.12065 -0.2794)
			(stroke
				(width 0.1)
				(type default)
			)
			(layer "F.Fab")
		)
		(fp_line
			(start -0.12065 0.2794)
			(end -0.12065 0.3048)
			(stroke
				(width 0.1)
				(type default)
			)
			(layer "F.Fab")
		)
		(fp_line
			(start -0.12065 0.3048)
			(end -0.67945 0.3048)
			(stroke
				(width 0.1)
				(type default)
			)
			(layer "F.Fab")
		)
		(fp_line
			(start 0.120396 0.2794)
			(end -0.12065 0.2794)
			(stroke
				(width 0.1)
				(type default)
			)
			(layer "F.Fab")
		)
		(fp_line
			(start 0.120396 0.3048)
			(end 0.120396 0.2794)
			(stroke
				(width 0.1)
				(type default)
			)
			(layer "F.Fab")
		)
		(fp_line
			(start 0.12065 -0.3048)
			(end 0.67945 -0.3048)
			(stroke
				(width 0.1)
				(type default)
			)
			(layer "F.Fab")
		)
		(fp_line
			(start 0.12065 -0.2794)
			(end 0.12065 -0.3048)
			(stroke
				(width 0.1)
				(type default)
			)
			(layer "F.Fab")
		)
		(fp_line
			(start 0.67945 -0.3048)
			(end 0.67945 0.3048)
			(stroke
				(width 0.1)
				(type default)
			)
			(layer "F.Fab")
		)
		(fp_line
			(start 0.67945 0.3048)
			(end 0.120396 0.3048)
			(stroke
				(width 0.1)
				(type default)
			)
			(layer "F.Fab")
		)
		(pad "1" smd circle
			(at -0.40005 0)
			(size 0 0)
			(layers "F.Cu" "F.Mask" "F.Paste")
			(net "P52V_HS2_UVLO_EN")
		)
		(pad "2" smd circle
			(at 0.40005 0)
			(size 0 0)
			(layers "F.Cu" "F.Mask" "F.Paste")
			(net "GND1_FIELD_SIGNAL")
		)
	)
	(footprint ""
		(layer "F.Cu")
		(at 125.675136 -82.677 180)
		(property "Reference" "PQ44"
			(at 2.104136 2.64033 0)
			(unlocked yes)
			(layer "F.SilkS")
			(effects
				(font
					(size 0.7874 0.5842)
					(thickness 0.1524)
				)
				(justify left)
			)
		)
		(property "Value" ""
			(at 0 0 180)
			(layer "F.Fab")
			(effects
				(font
					(size 1.27 1.27)
				)
			)
		)
		(duplicate_pad_numbers_are_jumpers no)
		(fp_line
			(start 1.905 1.651)
			(end -1.905 1.651)
			(stroke
				(width 0.1524)
				(type default)
			)
			(layer "F.SilkS")
		)
		(fp_line
			(start 1.905 -1.651)
			(end 1.905 1.651)
			(stroke
				(width 0.1524)
				(type default)
			)
			(layer "F.SilkS")
		)
		(fp_line
			(start -1.905 1.651)
			(end -1.905 -1.651)
			(stroke
				(width 0.1524)
				(type default)
			)
			(layer "F.SilkS")
		)
		(fp_line
			(start -1.905 -1.651)
			(end 1.905 -1.651)
			(stroke
				(width 0.1524)
				(type default)
			)
			(layer "F.SilkS")
		)
		(fp_line
			(start 1.249934 0.219964)
			(end 0.6985 0.219964)
			(stroke
				(width 0.1)
				(type default)
			)
			(layer "F.Fab")
		)
		(fp_line
			(start 1.249934 -0.219964)
			(end 1.249934 0.219964)
			(stroke
				(width 0.1)
				(type default)
			)
			(layer "F.Fab")
		)
		(fp_line
			(start 0.6985 1.524)
			(end -0.649986 1.524)
			(stroke
				(width 0.1)
				(type default)
			)
			(layer "F.Fab")
		)
		(fp_line
			(start 0.6985 0.219964)
			(end 0.6985 1.524)
			(stroke
				(width 0.1)
				(type default)
			)
			(layer "F.Fab")
		)
		(fp_line
			(start 0.6985 -0.219964)
			(end 1.249934 -0.219964)
			(stroke
				(width 0.1)
				(type default)
			)
			(layer "F.Fab")
		)
		(fp_line
			(start 0.6985 -1.524)
			(end 0.6985 -0.219964)
			(stroke
				(width 0.1)
				(type default)
			)
			(layer "F.Fab")
		)
		(fp_line
			(start -0.649986 1.524)
			(end -0.649986 1.169924)
			(stroke
				(width 0.1)
				(type default)
			)
			(layer "F.Fab")
		)
		(fp_line
			(start -0.649986 1.169924)
			(end -1.249934 1.169924)
			(stroke
				(width 0.1)
				(type default)
			)
			(layer "F.Fab")
		)
		(fp_line
			(start -0.649986 -1.169924)
			(end -0.649986 -1.524)
			(stroke
				(width 0.1)
				(type default)
			)
			(layer "F.Fab")
		)
		(fp_line
			(start -0.649986 -1.524)
			(end 0.6985 -1.524)
			(stroke
				(width 0.1)
				(type default)
			)
			(layer "F.Fab")
		)
		(fp_line
			(start -0.6985 0.729996)
			(end -0.6985 -0.729996)
			(stroke
				(width 0.1)
				(type default)
			)
			(layer "F.Fab")
		)
		(fp_line
			(start -0.6985 -0.729996)
			(end -1.249934 -0.729996)
			(stroke
				(width 0.1)
				(type default)
			)
			(layer "F.Fab")
		)
		(fp_line
			(start -1.249934 1.169924)
			(end -1.249934 0.729996)
			(stroke
				(width 0.1)
				(type default)
			)
			(layer "F.Fab")
		)
		(fp_line
			(start -1.249934 0.729996)
			(end -0.6985 0.729996)
			(stroke
				(width 0.1)
				(type default)
			)
			(layer "F.Fab")
		)
		(fp_line
			(start -1.249934 -0.729996)
			(end -1.249934 -1.169924)
			(stroke
				(width 0.1)
				(type default)
			)
			(layer "F.Fab")
		)
		(fp_line
			(start -1.249934 -1.169924)
			(end -0.649986 -1.169924)
			(stroke
				(width 0.1)
				(type default)
			)
			(layer "F.Fab")
		)
		(pad "B" smd rect
			(at -1.1176 -1.016 90)
			(size 1.016 1.27)
			(layers "F.Cu" "F.Mask" "F.Paste")
			(net "P52V_HS2_TEMP_R")
		)
		(pad "C" smd rect
			(at 1.1176 0 90)
			(size 1.016 1.27)
			(layers "F.Cu" "F.Mask" "F.Paste")
			(net "P52V_HS2_TEMP_R")
		)
		(pad "E" smd rect
			(at -1.1176 1.016 90)
			(size 1.016 1.27)
			(layers "F.Cu" "F.Mask" "F.Paste")
			(net "P52V_HS2_TEMPN_R")
		)
	)
	(footprint ""
		(layer "F.Cu")
		(at 449.326 -27.813)
		(property "Reference" "R331"
			(at 0 0 0)
			(layer "F.SilkS")
			(hide yes)
			(effects
				(font
					(size 1.27 1.27)
				)
			)
		)
		(property "Value" ""
			(at 0 0 0)
			(layer "F.Fab")
			(effects
				(font
					(size 1.27 1.27)
				)
			)
		)
		(duplicate_pad_numbers_are_jumpers no)
		(fp_line
			(start -0.7874 -0.4064)
			(end 0.7874 -0.4064)
			(stroke
				(width 0.1524)
				(type default)
			)
			(layer "F.SilkS")
		)
		(fp_line
			(start -0.7874 0.4064)
			(end -0.7874 -0.4064)
			(stroke
				(width 0.1524)
				(type default)
			)
			(layer "F.SilkS")
		)
		(fp_line
			(start 0.7874 -0.4064)
			(end 0.7874 0.4064)
			(stroke
				(width 0.1524)
				(type default)
			)
			(layer "F.SilkS")
		)
		(fp_line
			(start 0.7874 0.4064)
			(end -0.7874 0.4064)
			(stroke
				(width 0.1524)
				(type default)
			)
			(layer "F.SilkS")
		)
		(fp_line
			(start -0.67945 -0.305054)
			(end -0.12065 -0.305054)
			(stroke
				(width 0.1)
				(type default)
			)
			(layer "F.Fab")
		)
		(fp_line
			(start -0.67945 0.3048)
			(end -0.67945 -0.305054)
			(stroke
				(width 0.1)
				(type default)
			)
			(layer "F.Fab")
		)
		(fp_line
			(start -0.12065 -0.305054)
			(end -0.12065 -0.2794)
			(stroke
				(width 0.1)
				(type default)
			)
			(layer "F.Fab")
		)
		(fp_line
			(start -0.12065 -0.2794)
			(end 0.12065 -0.2794)
			(stroke
				(width 0.1)
				(type default)
			)
			(layer "F.Fab")
		)
		(fp_line
			(start -0.12065 0.2794)
			(end -0.12065 0.3048)
			(stroke
				(width 0.1)
				(type default)
			)
			(layer "F.Fab")
		)
		(fp_line
			(start -0.12065 0.3048)
			(end -0.67945 0.3048)
			(stroke
				(width 0.1)
				(type default)
			)
			(layer "F.Fab")
		)
		(fp_line
			(start 0.120396 0.2794)
			(end -0.12065 0.2794)
			(stroke
				(width 0.1)
				(type default)
			)
			(layer "F.Fab")
		)
		(fp_line
			(start 0.120396 0.3048)
			(end 0.120396 0.2794)
			(stroke
				(width 0.1)
				(type default)
			)
			(layer "F.Fab")
		)
		(fp_line
			(start 0.12065 -0.3048)
			(end 0.67945 -0.3048)
			(stroke
				(width 0.1)
				(type default)
			)
			(layer "F.Fab")
		)
		(fp_line
			(start 0.12065 -0.2794)
			(end 0.12065 -0.3048)
			(stroke
				(width 0.1)
				(type default)
			)
			(layer "F.Fab")
		)
		(fp_line
			(start 0.67945 -0.3048)
			(end 0.67945 0.3048)
			(stroke
				(width 0.1)
				(type default)
			)
			(layer "F.Fab")
		)
		(fp_line
			(start 0.67945 0.3048)
			(end 0.120396 0.3048)
			(stroke
				(width 0.1)
				(type default)
			)
			(layer "F.Fab")
		)
		(pad "1" smd circle
			(at -0.40005 0)
			(size 0 0)
			(layers "F.Cu" "F.Mask" "F.Paste")
			(net "SMB_PDB_FAN_1_SDA")
		)
		(pad "2" smd circle
			(at 0.40005 0)
			(size 0 0)
			(layers "F.Cu" "F.Mask" "F.Paste")
			(net "P3V3_AUX")
		)
	)
	(footprint ""
		(layer "F.Cu")
		(at 442.595 -41.402)
		(property "Reference" "U1"
			(at -4.8768 0.54737 0)
			(unlocked yes)
			(layer "F.SilkS")
			(effects
				(font
					(size 0.7874 0.5842)
					(thickness 0.1524)
				)
				(justify left)
			)
		)
		(property "Value" ""
			(at 0 0 0)
			(layer "F.Fab")
			(effects
				(font
					(size 1.27 1.27)
				)
			)
		)
		(duplicate_pad_numbers_are_jumpers no)
		(fp_line
			(start -1.3716 -1.524)
			(end -0.508 -1.524)
			(stroke
				(width 0.1524)
				(type default)
			)
			(layer "F.SilkS")
		)
		(fp_line
			(start -1.3716 1.524)
			(end -1.3716 -1.524)
			(stroke
				(width 0.1524)
				(type default)
			)
			(layer "F.SilkS")
		)
		(fp_line
			(start -0.508 -1.524)
			(end 0 -1.016)
			(stroke
				(width 0.1524)
				(type default)
			)
			(layer "F.SilkS")
		)
		(fp_line
			(start 0 -1.016)
			(end 0.508 -1.524)
			(stroke
				(width 0.1524)
				(type default)
			)
			(layer "F.SilkS")
		)
		(fp_line
			(start 0.508 -1.524)
			(end 1.3716 -1.524)
			(stroke
				(width 0.1524)
				(type default)
			)
			(layer "F.SilkS")
		)
		(fp_line
			(start 1.3716 -1.524)
			(end 1.3716 1.524)
			(stroke
				(width 0.1524)
				(type default)
			)
			(layer "F.SilkS")
		)
		(fp_line
			(start 1.3716 1.524)
			(end -1.3716 1.524)
			(stroke
				(width 0.1524)
				(type default)
			)
			(layer "F.SilkS")
		)
		(fp_poly
			(pts
				(xy -2.557272 -1.84912) (xy -1.932432 -1.84912) (xy -2.2606 -1.2954)
			)
			(stroke
				(width 0)
				(type default)
			)
			(fill yes)
			(layer "F.SilkS")
		)
		(fp_line
			(start -2.54 -1.0668)
			(end -1.5494 -1.0668)
			(stroke
				(width 0.1)
				(type default)
			)
			(layer "F.Fab")
		)
		(fp_line
			(start -2.54 1.0668)
			(end -2.54 -1.0668)
			(stroke
				(width 0.1)
				(type default)
			)
			(layer "F.Fab")
		)
		(fp_line
			(start -1.5494 -1.524)
			(end 1.5494 -1.524)
			(stroke
				(width 0.1)
				(type default)
			)
			(layer "F.Fab")
		)
		(fp_line
			(start -1.5494 -1.0668)
			(end -1.5494 -1.524)
			(stroke
				(width 0.1)
				(type default)
			)
			(layer "F.Fab")
		)
		(fp_line
			(start -1.5494 1.0668)
			(end -2.54 1.0668)
			(stroke
				(width 0.1)
				(type default)
			)
			(layer "F.Fab")
		)
		(fp_line
			(start -1.5494 1.0668)
			(end -1.5494 -1.0668)
			(stroke
				(width 0.1)
				(type default)
			)
			(layer "F.Fab")
		)
		(fp_line
			(start -1.5494 1.524)
			(end -1.5494 1.0668)
			(stroke
				(width 0.1)
				(type default)
			)
			(layer "F.Fab")
		)
		(fp_line
			(start 1.5494 -1.524)
			(end 1.5494 -1.0668)
			(stroke
				(width 0.1)
				(type default)
			)
			(layer "F.Fab")
		)
		(fp_line
			(start 1.5494 -1.0668)
			(end 1.5494 1.0668)
			(stroke
				(width 0.1)
				(type default)
			)
			(layer "F.Fab")
		)
		(fp_line
			(start 1.5494 -1.0668)
			(end 2.54 -1.0668)
			(stroke
				(width 0.1)
				(type default)
			)
			(layer "F.Fab")
		)
		(fp_line
			(start 1.5494 1.0668)
			(end 1.5494 1.524)
			(stroke
				(width 0.1)
				(type default)
			)
			(layer "F.Fab")
		)
		(fp_line
			(start 1.5494 1.524)
			(end -1.5494 1.524)
			(stroke
				(width 0.1)
				(type default)
			)
			(layer "F.Fab")
		)
		(fp_line
			(start 2.54 -1.0668)
			(end 2.54 1.0668)
			(stroke
				(width 0.1)
				(type default)
			)
			(layer "F.Fab")
		)
		(fp_line
			(start 2.54 1.0668)
			(end 1.5494 1.0668)
			(stroke
				(width 0.1)
				(type default)
			)
			(layer "F.Fab")
		)
		(fp_poly
			(pts
				(xy -3.60172 -0.719328) (xy -3.60172 -1.344168) (xy -3.048 -1.016)
			)
			(stroke
				(width 0)
				(type default)
			)
			(fill yes)
			(layer "F.Fab")
		)
		(pad "1" smd rect
			(at -2.232406 -0.975106 270)
			(size 0.3556 1.4224)
			(layers "F.Cu" "F.Mask" "F.Paste")
			(net "MB_MISC_I2C_EN")
		)
		(pad "2" smd rect
			(at -2.232406 -0.32512 270)
			(size 0.3556 1.4224)
			(layers "F.Cu" "F.Mask" "F.Paste")
			(net "SMB_PDB_MISC_SCL_R")
		)
		(pad "3" smd rect
			(at -2.232406 0.32512 270)
			(size 0.3556 1.4224)
			(layers "F.Cu" "F.Mask" "F.Paste")
			(net "SMB_PDB_SCL")
		)
		(pad "4" smd rect
			(at -2.232406 0.975106 270)
			(size 0.3556 1.4224)
			(layers "F.Cu" "F.Mask" "F.Paste")
			(net "GND")
		)
		(pad "5" smd rect
			(at 2.232406 0.975106 270)
			(size 0.3556 1.4224)
			(layers "F.Cu" "F.Mask" "F.Paste")
			(net "NC_U1_READY")
		)
		(pad "6" smd rect
			(at 2.232406 0.32512 270)
			(size 0.3556 1.4224)
			(layers "F.Cu" "F.Mask" "F.Paste")
			(net "SMB_PDB_SDA")
		)
		(pad "7" smd rect
			(at 2.232406 -0.32512 270)
			(size 0.3556 1.4224)
			(layers "F.Cu" "F.Mask" "F.Paste")
			(net "SMB_PDB_MISC_SDA_R")
		)
		(pad "8" smd rect
			(at 2.232406 -0.975106 270)
			(size 0.3556 1.4224)
			(layers "F.Cu" "F.Mask" "F.Paste")
			(net "P3V3_AUX")
		)
	)
	(footprint ""
		(layer "F.Cu")
		(at 164.211 -81.534 90)
		(property "Reference" "U44"
			(at -1.651 -1.793748 90)
			(unlocked yes)
			(layer "F.SilkS")
			(effects
				(font
					(size 0.7874 0.5842)
					(thickness 0.1524)
				)
				(justify left)
			)
		)
		(property "Value" ""
			(at 0 0 90)
			(layer "F.Fab")
			(effects
				(font
					(size 1.27 1.27)
				)
			)
		)
		(duplicate_pad_numbers_are_jumpers no)
		(fp_line
			(start 1.400048 -1.100074)
			(end -1.400048 -1.100074)
			(stroke
				(width 0.1524)
				(type default)
			)
			(layer "F.SilkS")
		)
		(fp_line
			(start 1.400048 -1.100074)
			(end 1.400048 1.100074)
			(stroke
				(width 0.1524)
				(type default)
			)
			(layer "F.SilkS")
		)
		(fp_line
			(start 1.400048 1.100074)
			(end -1.400048 1.100074)
			(stroke
				(width 0.1524)
				(type default)
			)
			(layer "F.SilkS")
		)
		(fp_line
			(start -1.400048 1.100074)
			(end -1.400048 -1.100074)
			(stroke
				(width 0.1524)
				(type default)
			)
			(layer "F.SilkS")
		)
		(fp_poly
			(pts
				(xy -1.590548 -0.649986) (xy -2.606548 -1.157986) (xy -2.606548 -0.141986)
			)
			(stroke
				(width 0)
				(type default)
			)
			(fill yes)
			(layer "F.SilkS")
		)
		(fp_line
			(start 0.674878 -1.100074)
			(end 0.674878 1.100074)
			(stroke
				(width 0.1)
				(type default)
			)
			(layer "F.Fab")
		)
		(fp_line
			(start -0.674878 -1.100074)
			(end 0.674878 -1.100074)
			(stroke
				(width 0.1)
				(type default)
			)
			(layer "F.Fab")
		)
		(fp_line
			(start 0.674878 1.100074)
			(end -0.674878 1.100074)
			(stroke
				(width 0.1)
				(type default)
			)
			(layer "F.Fab")
		)
		(fp_line
			(start -0.674878 1.100074)
			(end -0.674878 -1.100074)
			(stroke
				(width 0.1)
				(type default)
			)
			(layer "F.Fab")
		)
		(fp_poly
			(pts
				(xy -1.590548 -0.649986) (xy -2.606548 -1.157986) (xy -2.606548 -0.141986)
			)
			(stroke
				(width 0)
				(type default)
			)
			(fill yes)
			(layer "F.Fab")
		)
		(pad "1" smd rect
			(at -0.94996 -0.649986)
			(size 0.4318 0.6096)
			(layers "F.Cu" "F.Mask" "F.Paste")
			(net "Net_416")
		)
		(pad "2" smd rect
			(at -0.94996 0)
			(size 0.4318 0.6096)
			(layers "F.Cu" "F.Mask" "F.Paste")
			(net "FM_HS2_EN_BUSBAR")
		)
		(pad "3" smd rect
			(at -0.94996 0.649986)
			(size 0.4318 0.6096)
			(layers "F.Cu" "F.Mask" "F.Paste")
			(net "GND")
		)
		(pad "4" smd rect
			(at 0.94996 0.649986)
			(size 0.4318 0.6096)
			(layers "F.Cu" "F.Mask" "F.Paste")
			(net "FM_HS2_EN_BUSBAR_BUF")
		)
		(pad "5" smd rect
			(at 0.94996 -0.649986)
			(size 0.4318 0.6096)
			(layers "F.Cu" "F.Mask" "F.Paste")
			(net "P3V3_AUX")
		)
	)
)
